(kicad_pcb
	(version 20260206)
	(generator "pcbnew")
	(generator_version "10.0")
	(general
		(thickness 1.6)
		(legacy_teardrops no)
	)
	(paper "A4")
	(title_block
		(title "Bryce Canyon_IOM_IOC_16318-2_OCP.brd")
		(comment 1 "Bryce Canyon / footprints 399-405 of 1605")
	)
	(layers
		(0 "F.Cu" signal "TOP")
		(4 "In1.Cu" signal "L2GND")
		(6 "In2.Cu" signal "L3")
		(8 "In3.Cu" signal "L4VCC")
		(10 "In4.Cu" signal "L5VCC")
		(12 "In5.Cu" signal "L6")
		(14 "In6.Cu" signal "L7GND")
		(2 "B.Cu" signal "BOTTOM")
		(9 "F.Adhes" user "F.Adhesive")
		(11 "B.Adhes" user "B.Adhesive")
		(13 "F.Paste" user "Package Geometry/Pastemask Top")
		(15 "B.Paste" user "Package Geometry/Pastemask Bottom")
		(5 "F.SilkS" user "Ref Des/Silkscreen Top")
		(7 "B.SilkS" user "Ref Des/Silkscreen Bottom")
		(1 "F.Mask" user "Board Geometry/Soldermask Top")
		(3 "B.Mask" user "Board Geometry/Soldermask Bottom")
		(17 "Dwgs.User" user "User.Drawings")
		(19 "Cmts.User" user "User.Comments")
		(21 "Eco1.User" user "User.Eco1")
		(23 "Eco2.User" user "User.Eco2")
		(25 "Edge.Cuts" user "Board Geometry/Outline")
		(27 "Margin" user)
		(31 "F.CrtYd" user "Package Geometry/Place Bound Top")
		(29 "B.CrtYd" user "Package Geometry/Place Bound Bottom")
		(35 "F.Fab" user "Ref Des/Assembly Top")
		(33 "B.Fab" user "Ref Des/Assembly Bottom")
	)
	(footprint ""
		(layer "F.Cu")
		(at 36.7792 -165.5572)
		(property "Reference" "R740"
			(at 0 0 0)
			(layer "F.SilkS")
			(hide yes)
			(effects
				(font
					(size 1.27 1.27)
				)
			)
		)
		(property "Value" "4K7R2F-GP"
			(at 0.064008 -3.993896 0)
			(unlocked yes)
			(layer "F.Fab")
			(hide yes)
			(effects
				(font
					(size 1.016 1.016)
					(thickness 0.1524)
				)
			)
		)
		(property "Device Type" "R402H16"
			(at 0.064008 -5.517896 0)
			(unlocked yes)
			(layer "F.Fab")
			(hide yes)
			(effects
				(font
					(size 1.016 1.016)
					(thickness 0.1524)
				)
			)
		)
		(duplicate_pad_numbers_are_jumpers no)
		(fp_line
			(start -0.508 -0.9398)
			(end -0.508 0.9398)
			(stroke
				(width 0.1524)
				(type default)
			)
			(layer "F.SilkS")
		)
		(fp_line
			(start 0.508 -0.9398)
			(end -0.508 -0.9398)
			(stroke
				(width 0.1524)
				(type default)
			)
			(layer "F.SilkS")
		)
		(fp_rect
			(start -0.508 0.9398)
			(end 0.508 -0.9398)
			(stroke
				(width 0)
				(type default)
			)
			(fill no)
			(layer "F.CrtYd")
		)
		(fp_rect
			(start -0.508 0.9398)
			(end 0.508 -0.9398)
			(stroke
				(width 0)
				(type default)
			)
			(fill no)
			(layer "F.Fab")
		)
		(pad "1" smd custom
			(at 0 -0.4445)
			(size 0.1397 0.1397)
			(layers "F.Cu" "F.Mask" "F.Paste")
			(net "GND")
			(options
				(clearance outline)
				(anchor circle)
			)
			(primitives
				(gr_poly
					(pts
						(arc
							(start -0.1778 -0.2794)
							(mid -0.249642 -0.249642)
							(end -0.2794 -0.1778)
						)
						(arc
							(start -0.2794 0.1778)
							(mid -0.249642 0.249642)
							(end -0.1778 0.2794)
						)
						(arc
							(start 0.1778 0.2794)
							(mid 0.249642 0.249642)
							(end 0.2794 0.1778)
						)
						(arc
							(start 0.2794 -0.1778)
							(mid 0.249642 -0.249642)
							(end 0.1778 -0.2794)
						)
					)
					(width 0)
					(fill yes)
				)
			)
		)
		(pad "2" smd custom
			(at 0 0.4445)
			(size 0.1397 0.1397)
			(layers "F.Cu" "F.Mask" "F.Paste")
			(net "IOM_TYPE0")
			(options
				(clearance outline)
				(anchor circle)
			)
			(primitives
				(gr_poly
					(pts
						(arc
							(start -0.1778 -0.2794)
							(mid -0.249642 -0.249642)
							(end -0.2794 -0.1778)
						)
						(arc
							(start -0.2794 0.1778)
							(mid -0.249642 0.249642)
							(end -0.1778 0.2794)
						)
						(arc
							(start 0.1778 0.2794)
							(mid 0.249642 0.249642)
							(end 0.2794 0.1778)
						)
						(arc
							(start 0.2794 -0.1778)
							(mid 0.249642 -0.249642)
							(end 0.1778 -0.2794)
						)
					)
					(width 0)
					(fill yes)
				)
			)
		)
	)
	(footprint ""
		(layer "F.Cu")
		(at 181.24805 -140.837158)
		(property "Reference" "R470"
			(at 0 0 0)
			(layer "F.SilkS")
			(hide yes)
			(effects
				(font
					(size 1.27 1.27)
				)
			)
		)
		(property "Value" "200KR2F-L-GP"
			(at 0.064008 -3.993896 0)
			(unlocked yes)
			(layer "F.Fab")
			(hide yes)
			(effects
				(font
					(size 1.016 1.016)
					(thickness 0.1524)
				)
			)
		)
		(property "Device Type" "R402H16"
			(at 0.064008 -5.517896 0)
			(unlocked yes)
			(layer "F.Fab")
			(hide yes)
			(effects
				(font
					(size 1.016 1.016)
					(thickness 0.1524)
				)
			)
		)
		(duplicate_pad_numbers_are_jumpers no)
		(fp_line
			(start -0.508 -0.9398)
			(end -0.508 0.9398)
			(stroke
				(width 0.1524)
				(type default)
			)
			(layer "F.SilkS")
		)
		(fp_line
			(start 0.508 -0.9398)
			(end -0.508 -0.9398)
			(stroke
				(width 0.1524)
				(type default)
			)
			(layer "F.SilkS")
		)
		(fp_rect
			(start -0.508 0.9398)
			(end 0.508 -0.9398)
			(stroke
				(width 0)
				(type default)
			)
			(fill no)
			(layer "F.CrtYd")
		)
		(fp_rect
			(start -0.508 0.9398)
			(end 0.508 -0.9398)
			(stroke
				(width 0)
				(type default)
			)
			(fill no)
			(layer "F.Fab")
		)
		(pad "1" smd custom
			(at 0 -0.4445)
			(size 0.1397 0.1397)
			(layers "F.Cu" "F.Mask" "F.Paste")
			(net "P5V_MODE")
			(options
				(clearance outline)
				(anchor circle)
			)
			(primitives
				(gr_poly
					(pts
						(arc
							(start -0.1778 -0.2794)
							(mid -0.249642 -0.249642)
							(end -0.2794 -0.1778)
						)
						(arc
							(start -0.2794 0.1778)
							(mid -0.249642 0.249642)
							(end -0.1778 0.2794)
						)
						(arc
							(start 0.1778 0.2794)
							(mid 0.249642 0.249642)
							(end 0.2794 0.1778)
						)
						(arc
							(start 0.2794 -0.1778)
							(mid 0.249642 -0.249642)
							(end 0.1778 -0.2794)
						)
					)
					(width 0)
					(fill yes)
				)
			)
		)
		(pad "2" smd custom
			(at 0 0.4445)
			(size 0.1397 0.1397)
			(layers "F.Cu" "F.Mask" "F.Paste")
			(net "PWRGD_P5V_STBY")
			(options
				(clearance outline)
				(anchor circle)
			)
			(primitives
				(gr_poly
					(pts
						(arc
							(start -0.1778 -0.2794)
							(mid -0.249642 -0.249642)
							(end -0.2794 -0.1778)
						)
						(arc
							(start -0.2794 0.1778)
							(mid -0.249642 0.249642)
							(end -0.1778 0.2794)
						)
						(arc
							(start 0.1778 0.2794)
							(mid 0.249642 0.249642)
							(end 0.2794 0.1778)
						)
						(arc
							(start 0.2794 -0.1778)
							(mid 0.249642 -0.249642)
							(end 0.1778 -0.2794)
						)
					)
					(width 0)
					(fill yes)
				)
			)
		)
	)
	(footprint ""
		(layer "F.Cu")
		(at 60.2488 -167.4114 90)
		(property "Reference" "R77"
			(at 0 0 90)
			(layer "F.SilkS")
			(hide yes)
			(effects
				(font
					(size 1.27 1.27)
				)
			)
		)
		(property "Value" "10KR2F-2-GP"
			(at 0.064008 -3.993896 90)
			(unlocked yes)
			(layer "F.Fab")
			(hide yes)
			(effects
				(font
					(size 1.016 1.016)
					(thickness 0.1524)
				)
			)
		)
		(property "Device Type" "R402H16"
			(at 0.064008 -5.517896 90)
			(unlocked yes)
			(layer "F.Fab")
			(hide yes)
			(effects
				(font
					(size 1.016 1.016)
					(thickness 0.1524)
				)
			)
		)
		(duplicate_pad_numbers_are_jumpers no)
		(fp_line
			(start 0.508 -0.9398)
			(end -0.508 -0.9398)
			(stroke
				(width 0.1524)
				(type default)
			)
			(layer "F.SilkS")
		)
		(fp_line
			(start -0.508 -0.9398)
			(end -0.508 0.9398)
			(stroke
				(width 0.1524)
				(type default)
			)
			(layer "F.SilkS")
		)
		(fp_rect
			(start -0.508 0.9398)
			(end 0.508 -0.9398)
			(stroke
				(width 0)
				(type default)
			)
			(fill no)
			(layer "F.CrtYd")
		)
		(fp_rect
			(start -0.508 0.9398)
			(end 0.508 -0.9398)
			(stroke
				(width 0)
				(type default)
			)
			(fill no)
			(layer "F.Fab")
		)
		(pad "1" smd custom
			(at 0 -0.4445 90)
			(size 0.1397 0.1397)
			(layers "F.Cu" "F.Mask" "F.Paste")
			(net "P3V3_STBY")
			(options
				(clearance outline)
				(anchor circle)
			)
			(primitives
				(gr_poly
					(pts
						(arc
							(start -0.1778 -0.2794)
							(mid -0.249642 -0.249642)
							(end -0.2794 -0.1778)
						)
						(arc
							(start -0.2794 0.1778)
							(mid -0.249642 0.249642)
							(end -0.1778 0.2794)
						)
						(arc
							(start 0.1778 0.2794)
							(mid 0.249642 0.249642)
							(end 0.2794 0.1778)
						)
						(arc
							(start 0.2794 -0.1778)
							(mid 0.249642 -0.249642)
							(end 0.1778 -0.2794)
						)
					)
					(width 0)
					(fill yes)
				)
			)
		)
		(pad "2" smd custom
			(at 0 0.4445 90)
			(size 0.1397 0.1397)
			(layers "F.Cu" "F.Mask" "F.Paste")
			(net "FM_TPM_PRSNT_RST_N")
			(options
				(clearance outline)
				(anchor circle)
			)
			(primitives
				(gr_poly
					(pts
						(arc
							(start -0.1778 -0.2794)
							(mid -0.249642 -0.249642)
							(end -0.2794 -0.1778)
						)
						(arc
							(start -0.2794 0.1778)
							(mid -0.249642 0.249642)
							(end -0.1778 0.2794)
						)
						(arc
							(start 0.1778 0.2794)
							(mid 0.249642 0.249642)
							(end 0.2794 0.1778)
						)
						(arc
							(start 0.2794 -0.1778)
							(mid 0.249642 -0.249642)
							(end 0.1778 -0.2794)
						)
					)
					(width 0)
					(fill yes)
				)
			)
		)
	)
	(footprint ""
		(layer "F.Cu")
		(at 53.47208 -160.30194)
		(property "Reference" "C84"
			(at 0 0 0)
			(layer "F.SilkS")
			(hide yes)
			(effects
				(font
					(size 1.27 1.27)
				)
			)
		)
		(property "Value" "SCD1U16V2KX-3GP"
			(at 1.1811 -2.7051 0)
			(unlocked yes)
			(layer "F.Fab")
			(hide yes)
			(effects
				(font
					(size 1.016 1.016)
					(thickness 0.1524)
				)
			)
		)
		(property "Device Type" "C402H22"
			(at 1.1811 -4.2291 0)
			(unlocked yes)
			(layer "F.Fab")
			(hide yes)
			(effects
				(font
					(size 1.016 1.016)
					(thickness 0.1524)
				)
			)
		)
		(duplicate_pad_numbers_are_jumpers no)
		(fp_rect
			(start -0.4318 0.9525)
			(end 0.4318 -0.9525)
			(stroke
				(width 0)
				(type default)
			)
			(fill no)
			(layer "F.CrtYd")
		)
		(fp_rect
			(start -0.4318 0.9525)
			(end 0.4318 -0.9525)
			(stroke
				(width 0)
				(type default)
			)
			(fill no)
			(layer "F.Fab")
		)
		(pad "1" smd custom
			(at 0 -0.4445)
			(size 0.1524 0.1524)
			(layers "F.Cu" "F.Mask" "F.Paste")
			(net "ADCAV33")
			(options
				(clearance outline)
				(anchor circle)
			)
			(primitives
				(gr_poly
					(pts
						(arc
							(start 0.3048 -0.2032)
							(mid 0.275042 -0.275042)
							(end 0.2032 -0.3048)
						)
						(arc
							(start -0.2032 -0.3048)
							(mid -0.275042 -0.275042)
							(end -0.3048 -0.2032)
						)
						(arc
							(start -0.3048 0.2032)
							(mid -0.275042 0.275042)
							(end -0.2032 0.3048)
						)
						(arc
							(start 0.2032 0.3048)
							(mid 0.275042 0.275042)
							(end 0.3048 0.2032)
						)
					)
					(width 0)
					(fill yes)
				)
			)
		)
		(pad "2" smd custom
			(at 0 0.4445)
			(size 0.1524 0.1524)
			(layers "F.Cu" "F.Mask" "F.Paste")
			(net "ADCVREFFP")
			(options
				(clearance outline)
				(anchor circle)
			)
			(primitives
				(gr_poly
					(pts
						(arc
							(start 0.3048 -0.2032)
							(mid 0.275042 -0.275042)
							(end 0.2032 -0.3048)
						)
						(arc
							(start -0.2032 -0.3048)
							(mid -0.275042 -0.275042)
							(end -0.3048 -0.2032)
						)
						(arc
							(start -0.3048 0.2032)
							(mid -0.275042 0.275042)
							(end -0.2032 0.3048)
						)
						(arc
							(start 0.2032 0.3048)
							(mid 0.275042 0.275042)
							(end 0.3048 0.2032)
						)
					)
					(width 0)
					(fill yes)
				)
			)
		)
	)
	(footprint ""
		(layer "F.Cu")
		(at 94.153228 -49.421796)
		(property "Reference" "R500"
			(at 0 0 0)
			(layer "F.SilkS")
			(hide yes)
			(effects
				(font
					(size 1.27 1.27)
				)
			)
		)
		(property "Value" "2K2R2J-2-GP"
			(at 0.064008 -3.993896 0)
			(unlocked yes)
			(layer "F.Fab")
			(hide yes)
			(effects
				(font
					(size 1.016 1.016)
					(thickness 0.1524)
				)
			)
		)
		(property "Device Type" "R402H16"
			(at 0.064008 -5.517896 0)
			(unlocked yes)
			(layer "F.Fab")
			(hide yes)
			(effects
				(font
					(size 1.016 1.016)
					(thickness 0.1524)
				)
			)
		)
		(duplicate_pad_numbers_are_jumpers no)
		(fp_line
			(start -0.508 -0.9398)
			(end -0.508 0.9398)
			(stroke
				(width 0.1524)
				(type default)
			)
			(layer "F.SilkS")
		)
		(fp_line
			(start 0.508 -0.9398)
			(end -0.508 -0.9398)
			(stroke
				(width 0.1524)
				(type default)
			)
			(layer "F.SilkS")
		)
		(fp_rect
			(start -0.508 0.9398)
			(end 0.508 -0.9398)
			(stroke
				(width 0)
				(type default)
			)
			(fill no)
			(layer "F.CrtYd")
		)
		(fp_rect
			(start -0.508 0.9398)
			(end 0.508 -0.9398)
			(stroke
				(width 0)
				(type default)
			)
			(fill no)
			(layer "F.Fab")
		)
		(pad "1" smd custom
			(at 0 -0.4445)
			(size 0.1397 0.1397)
			(layers "F.Cu" "F.Mask" "F.Paste")
			(net "P3V3_STBY")
			(options
				(clearance outline)
				(anchor circle)
			)
			(primitives
				(gr_poly
					(pts
						(arc
							(start -0.1778 -0.2794)
							(mid -0.249642 -0.249642)
							(end -0.2794 -0.1778)
						)
						(arc
							(start -0.2794 0.1778)
							(mid -0.249642 0.249642)
							(end -0.1778 0.2794)
						)
						(arc
							(start 0.1778 0.2794)
							(mid 0.249642 0.249642)
							(end 0.2794 0.1778)
						)
						(arc
							(start 0.2794 -0.1778)
							(mid 0.249642 -0.249642)
							(end 0.1778 -0.2794)
						)
					)
					(width 0)
					(fill yes)
				)
			)
		)
		(pad "2" smd custom
			(at 0 0.4445)
			(size 0.1397 0.1397)
			(layers "F.Cu" "F.Mask" "F.Paste")
			(net "PQ2_G")
			(options
				(clearance outline)
				(anchor circle)
			)
			(primitives
				(gr_poly
					(pts
						(arc
							(start -0.1778 -0.2794)
							(mid -0.249642 -0.249642)
							(end -0.2794 -0.1778)
						)
						(arc
							(start -0.2794 0.1778)
							(mid -0.249642 0.249642)
							(end -0.1778 0.2794)
						)
						(arc
							(start 0.1778 0.2794)
							(mid 0.249642 0.249642)
							(end 0.2794 0.1778)
						)
						(arc
							(start 0.2794 -0.1778)
							(mid 0.249642 -0.249642)
							(end 0.1778 -0.2794)
						)
					)
					(width 0)
					(fill yes)
				)
			)
		)
	)
	(footprint ""
		(layer "F.Cu")
		(at 89.908888 -48.245776 180)
		(property "Reference" "C186"
			(at 0 0 180)
			(layer "F.SilkS")
			(hide yes)
			(effects
				(font
					(size 1.27 1.27)
				)
			)
		)
		(property "Value" "SCD47U25V3KX-3-GP"
			(at 0 -2.8194 180)
			(unlocked yes)
			(layer "F.Fab")
			(hide yes)
			(effects
				(font
					(size 1.016 1.016)
					(thickness 0.1524)
				)
			)
		)
		(property "Device Type" "C603H36"
			(at 0 -4.3434 180)
			(unlocked yes)
			(layer "F.Fab")
			(hide yes)
			(effects
				(font
					(size 1.016 1.016)
					(thickness 0.1524)
				)
			)
		)
		(duplicate_pad_numbers_are_jumpers no)
		(fp_line
			(start 0.508 0)
			(end -0.508 0)
			(stroke
				(width 0.2032)
				(type default)
			)
			(layer "F.SilkS")
		)
		(fp_rect
			(start -0.5842 1.3335)
			(end 0.5842 -1.3335)
			(stroke
				(width 0)
				(type default)
			)
			(fill no)
			(layer "F.CrtYd")
		)
		(fp_rect
			(start -0.5842 1.3335)
			(end 0.5842 -1.3335)
			(stroke
				(width 0)
				(type default)
			)
			(fill no)
			(layer "F.Fab")
		)
		(pad "1" smd custom
			(at 0 -0.762 180)
			(size 0.2159 0.2159)
			(layers "F.Cu" "F.Mask" "F.Paste")
			(net "PQ2_D")
			(options
				(clearance outline)
				(anchor circle)
			)
			(primitives
				(gr_poly
					(pts
						(arc
							(start -0.3302 -0.4318)
							(mid -0.402042 -0.402042)
							(end -0.4318 -0.3302)
						)
						(arc
							(start -0.4318 0.3302)
							(mid -0.402042 0.402042)
							(end -0.3302 0.4318)
						)
						(arc
							(start 0.3302 0.4318)
							(mid 0.402042 0.402042)
							(end 0.4318 0.3302)
						)
						(arc
							(start 0.4318 -0.3302)
							(mid 0.402042 -0.402042)
							(end 0.3302 -0.4318)
						)
					)
					(width 0)
					(fill yes)
				)
			)
		)
		(pad "2" smd custom
			(at 0 0.762 180)
			(size 0.2159 0.2159)
			(layers "F.Cu" "F.Mask" "F.Paste")
			(net "P3V3")
			(options
				(clearance outline)
				(anchor circle)
			)
			(primitives
				(gr_poly
					(pts
						(arc
							(start -0.3302 -0.4318)
							(mid -0.402042 -0.402042)
							(end -0.4318 -0.3302)
						)
						(arc
							(start -0.4318 0.3302)
							(mid -0.402042 0.402042)
							(end -0.3302 0.4318)
						)
						(arc
							(start 0.3302 0.4318)
							(mid 0.402042 0.402042)
							(end 0.4318 0.3302)
						)
						(arc
							(start 0.4318 -0.3302)
							(mid 0.402042 -0.402042)
							(end 0.3302 -0.4318)
						)
					)
					(width 0)
					(fill yes)
				)
			)
		)
	)
	(footprint ""
		(layer "F.Cu")
		(at 93.972126 -148.223732)
		(property "Reference" "C18"
			(at 0 0 0)
			(layer "F.SilkS")
			(hide yes)
			(effects
				(font
					(size 1.27 1.27)
				)
			)
		)
		(property "Value" "SC1U16V3KX-5GP"
			(at 0 -2.8194 0)
			(unlocked yes)
			(layer "F.Fab")
			(hide yes)
			(effects
				(font
					(size 1.016 1.016)
					(thickness 0.1524)
				)
			)
		)
		(property "Device Type" "C603H36"
			(at 0 -4.3434 0)
			(unlocked yes)
			(layer "F.Fab")
			(hide yes)
			(effects
				(font
					(size 1.016 1.016)
					(thickness 0.1524)
				)
			)
		)
		(duplicate_pad_numbers_are_jumpers no)
		(fp_line
			(start 0.508 0)
			(end -0.508 0)
			(stroke
				(width 0.2032)
				(type default)
			)
			(layer "F.SilkS")
		)
		(fp_rect
			(start -0.5842 1.3335)
			(end 0.5842 -1.3335)
			(stroke
				(width 0)
				(type default)
			)
			(fill no)
			(layer "F.CrtYd")
		)
		(fp_rect
			(start -0.5842 1.3335)
			(end 0.5842 -1.3335)
			(stroke
				(width 0)
				(type default)
			)
			(fill no)
			(layer "F.Fab")
		)
		(pad "1" smd custom
			(at 0 -0.762)
			(size 0.2159 0.2159)
			(layers "F.Cu" "F.Mask" "F.Paste")
			(net "CRFILT")
			(options
				(clearance outline)
				(anchor circle)
			)
			(primitives
				(gr_poly
					(pts
						(arc
							(start -0.3302 -0.4318)
							(mid -0.402042 -0.402042)
							(end -0.4318 -0.3302)
						)
						(arc
							(start -0.4318 0.3302)
							(mid -0.402042 0.402042)
							(end -0.3302 0.4318)
						)
						(arc
							(start 0.3302 0.4318)
							(mid 0.402042 0.402042)
							(end 0.4318 0.3302)
						)
						(arc
							(start 0.4318 -0.3302)
							(mid 0.402042 -0.402042)
							(end 0.3302 -0.4318)
						)
					)
					(width 0)
					(fill yes)
				)
			)
		)
		(pad "2" smd custom
			(at 0 0.762)
			(size 0.2159 0.2159)
			(layers "F.Cu" "F.Mask" "F.Paste")
			(net "GND")
			(options
				(clearance outline)
				(anchor circle)
			)
			(primitives
				(gr_poly
					(pts
						(arc
							(start -0.3302 -0.4318)
							(mid -0.402042 -0.402042)
							(end -0.4318 -0.3302)
						)
						(arc
							(start -0.4318 0.3302)
							(mid -0.402042 0.402042)
							(end -0.3302 0.4318)
						)
						(arc
							(start 0.3302 0.4318)
							(mid 0.402042 0.402042)
							(end 0.4318 0.3302)
						)
						(arc
							(start 0.4318 -0.3302)
							(mid 0.402042 -0.402042)
							(end 0.3302 -0.4318)
						)
					)
					(width 0)
					(fill yes)
				)
			)
		)
	)
)
